(kicad_pcb
	(version 20260206)
	(generator "pcbnew")
	(generator_version "10.0")
	(general
		(thickness 1.6)
		(legacy_teardrops no)
	)
	(paper "A4")
	(title_block
		(title "04192023_DAF0TMB3IC0_F0TG_MB_C_brd_V02_OCP.brd")
		(comment 1 "Grand Teton / footprints 5880-5885 of 8354")
	)
	(layers
		(0 "F.Cu" signal "TOP")
		(4 "In1.Cu" signal "GND")
		(6 "In2.Cu" signal "IN1")
		(8 "In3.Cu" signal "GND1")
		(10 "In4.Cu" signal "IN2")
		(12 "In5.Cu" signal "GND2")
		(14 "In6.Cu" signal "IN3")
		(16 "In7.Cu" signal "GND3")
		(18 "In8.Cu" signal "VCC")
		(20 "In9.Cu" signal "VCC1")
		(22 "In10.Cu" signal "GND4")
		(24 "In11.Cu" signal "IN4")
		(26 "In12.Cu" signal "GND5")
		(28 "In13.Cu" signal "IN5")
		(30 "In14.Cu" signal "GND6")
		(32 "In15.Cu" signal "IN6")
		(34 "In16.Cu" signal "GND7")
		(2 "B.Cu" signal "BOTTOM")
		(9 "F.Adhes" user "F.Adhesive")
		(11 "B.Adhes" user "B.Adhesive")
		(13 "F.Paste" user "Package Geometry/Pastemask Top")
		(15 "B.Paste" user "Package Geometry/Pastemask Bottom")
		(5 "F.SilkS" user "Ref Des/Silkscreen Top")
		(7 "B.SilkS" user "Ref Des/Silkscreen Bottom")
		(1 "F.Mask" user "Board Geometry/Soldermask Top")
		(3 "B.Mask" user "Board Geometry/Soldermask Bottom")
		(17 "Dwgs.User" user "User.Drawings")
		(19 "Cmts.User" user "User.Comments")
		(21 "Eco1.User" user "User.Eco1")
		(23 "Eco2.User" user "User.Eco2")
		(25 "Edge.Cuts" user "Board Geometry/Outline")
		(27 "Margin" user)
		(31 "F.CrtYd" user "Package Geometry/Place Bound Top")
		(29 "B.CrtYd" user "Package Geometry/Place Bound Bottom")
		(35 "F.Fab" user "Ref Des/Assembly Top")
		(33 "B.Fab" user "Ref Des/Assembly Bottom")
	)
	(footprint ""
		(layer "B.Cu")
		(at 6.649974 -373.339614 90)
		(property "Reference" "PC6628"
			(at -3.388614 -2.993644 270)
			(unlocked yes)
			(layer "B.SilkS")
			(effects
				(font
					(size 0.7874 0.5842)
					(thickness 0.1524)
				)
				(justify left mirror)
			)
		)
		(property "Value" ""
			(at 0 0 90)
			(layer "B.Fab")
			(effects
				(font
					(size 1.27 1.27)
				)
				(justify mirror)
			)
		)
		(duplicate_pad_numbers_are_jumpers no)
		(fp_line
			(start 4.84378 -2.150618)
			(end 4.53898 -2.150618)
			(stroke
				(width 0.1524)
				(type default)
			)
			(layer "B.SilkS")
		)
		(fp_line
			(start 4.84378 -2.150618)
			(end 4.842256 2.163064)
			(stroke
				(width 0.1524)
				(type default)
			)
			(layer "B.SilkS")
		)
		(fp_line
			(start 4.69138 -2.150618)
			(end 4.692396 2.161032)
			(stroke
				(width 0.1524)
				(type default)
			)
			(layer "B.SilkS")
		)
		(fp_line
			(start 4.53898 -2.150618)
			(end 4.539742 2.152142)
			(stroke
				(width 0.1524)
				(type default)
			)
			(layer "B.SilkS")
		)
		(fp_line
			(start 4.53898 -2.15011)
			(end -3.820414 -2.15011)
			(stroke
				(width 0.1524)
				(type default)
			)
			(layer "B.SilkS")
		)
		(fp_line
			(start -4.53898 -1.950974)
			(end -4.53898 2.15011)
			(stroke
				(width 0.1524)
				(type default)
			)
			(layer "B.SilkS")
		)
		(fp_line
			(start 4.53898 2.15011)
			(end 4.53898 -2.15011)
			(stroke
				(width 0.1524)
				(type default)
			)
			(layer "B.SilkS")
		)
		(fp_line
			(start -4.53898 2.15011)
			(end 4.53898 2.15011)
			(stroke
				(width 0.1524)
				(type default)
			)
			(layer "B.SilkS")
		)
		(fp_line
			(start 4.83108 2.150364)
			(end 4.447794 2.149348)
			(stroke
				(width 0.1524)
				(type default)
			)
			(layer "B.SilkS")
		)
		(fp_line
			(start 3.64998 -2.15011)
			(end -3.64998 -2.15011)
			(stroke
				(width 0.1)
				(type default)
			)
			(layer "B.Fab")
		)
		(fp_line
			(start -3.64998 -2.15011)
			(end -3.64998 2.15011)
			(stroke
				(width 0.1)
				(type default)
			)
			(layer "B.Fab")
		)
		(fp_line
			(start 3.64998 2.15011)
			(end 3.64998 -2.15011)
			(stroke
				(width 0.1)
				(type default)
			)
			(layer "B.Fab")
		)
		(fp_line
			(start -3.64998 2.15011)
			(end 3.64998 2.15011)
			(stroke
				(width 0.1)
				(type default)
			)
			(layer "B.Fab")
		)
		(fp_text user "-"
			(at -4.404614 -1.919224 90)
			(unlocked yes)
			(layer "B.SilkS")
			(effects
				(font
					(size 1.905 1.4224)
					(thickness 0.1524)
				)
				(justify left mirror)
			)
		)
		(fp_text user "+"
			(at 6.214872 -0.337058 90)
			(unlocked yes)
			(layer "B.SilkS")
			(effects
				(font
					(size 1.905 1.4224)
					(thickness 0.1524)
				)
				(justify left mirror)
			)
		)
		(fp_text user "+"
			(at 6.214872 -0.337058 90)
			(unlocked yes)
			(layer "B.Fab")
			(effects
				(font
					(size 1.905 1.4224)
					(thickness 0.1524)
				)
				(justify left mirror)
			)
		)
		(fp_text user "-"
			(at -4.313174 -0.094488 90)
			(unlocked yes)
			(layer "B.Fab")
			(effects
				(font
					(size 1.905 1.4224)
					(thickness 0.1524)
				)
				(justify left mirror)
			)
		)
		(pad "1" smd rect
			(at 3.199892 0 270)
			(size 2.413 2.8194)
			(layers "B.Cu" "B.Mask" "B.Paste")
			(net "P0V9_CPU1_RT_2D")
		)
		(pad "2" smd rect
			(at -3.199892 0 270)
			(size 2.413 2.8194)
			(layers "B.Cu" "B.Mask" "B.Paste")
			(net "GND")
		)
	)
	(footprint ""
		(layer "B.Cu")
		(at 371.551454 -252.54331)
		(property "Reference" "C2151"
			(at 0 0 0)
			(layer "B.SilkS")
			(hide yes)
			(effects
				(font
					(size 1.27 1.27)
				)
				(justify mirror)
			)
		)
		(property "Value" ""
			(at 0 0 0)
			(layer "B.Fab")
			(effects
				(font
					(size 1.27 1.27)
				)
				(justify mirror)
			)
		)
		(duplicate_pad_numbers_are_jumpers no)
		(fp_line
			(start -0.7874 -0.4064)
			(end -0.7874 0.4064)
			(stroke
				(width 0.1524)
				(type default)
			)
			(layer "B.SilkS")
		)
		(fp_line
			(start -0.7874 0.4064)
			(end 0.7874 0.4064)
			(stroke
				(width 0.1524)
				(type default)
			)
			(layer "B.SilkS")
		)
		(fp_line
			(start 0.7874 -0.4064)
			(end -0.7874 -0.4064)
			(stroke
				(width 0.1524)
				(type default)
			)
			(layer "B.SilkS")
		)
		(fp_line
			(start 0.7874 0.4064)
			(end 0.7874 -0.4064)
			(stroke
				(width 0.1524)
				(type default)
			)
			(layer "B.SilkS")
		)
		(fp_line
			(start -0.67945 -0.3048)
			(end -0.67945 0.3048)
			(stroke
				(width 0.1)
				(type default)
			)
			(layer "B.Fab")
		)
		(fp_line
			(start -0.67945 0.3048)
			(end -0.120396 0.3048)
			(stroke
				(width 0.1)
				(type default)
			)
			(layer "B.Fab")
		)
		(fp_line
			(start -0.12065 -0.3048)
			(end -0.67945 -0.3048)
			(stroke
				(width 0.1)
				(type default)
			)
			(layer "B.Fab")
		)
		(fp_line
			(start -0.12065 -0.2794)
			(end -0.12065 -0.3048)
			(stroke
				(width 0.1)
				(type default)
			)
			(layer "B.Fab")
		)
		(fp_line
			(start -0.120396 0.2794)
			(end 0.12065 0.2794)
			(stroke
				(width 0.1)
				(type default)
			)
			(layer "B.Fab")
		)
		(fp_line
			(start -0.120396 0.3048)
			(end -0.120396 0.2794)
			(stroke
				(width 0.1)
				(type default)
			)
			(layer "B.Fab")
		)
		(fp_line
			(start 0.12065 -0.305054)
			(end 0.12065 -0.2794)
			(stroke
				(width 0.1)
				(type default)
			)
			(layer "B.Fab")
		)
		(fp_line
			(start 0.12065 -0.2794)
			(end -0.12065 -0.2794)
			(stroke
				(width 0.1)
				(type default)
			)
			(layer "B.Fab")
		)
		(fp_line
			(start 0.12065 0.2794)
			(end 0.12065 0.3048)
			(stroke
				(width 0.1)
				(type default)
			)
			(layer "B.Fab")
		)
		(fp_line
			(start 0.12065 0.3048)
			(end 0.67945 0.3048)
			(stroke
				(width 0.1)
				(type default)
			)
			(layer "B.Fab")
		)
		(fp_line
			(start 0.67945 -0.305054)
			(end 0.12065 -0.305054)
			(stroke
				(width 0.1)
				(type default)
			)
			(layer "B.Fab")
		)
		(fp_line
			(start 0.67945 0.3048)
			(end 0.67945 -0.305054)
			(stroke
				(width 0.1)
				(type default)
			)
			(layer "B.Fab")
		)
		(pad "1" smd circle
			(at 0.40005 0 180)
			(size 0 0)
			(layers "B.Cu" "B.Mask" "B.Paste")
			(net "PVDDCR_SOC_P0")
		)
		(pad "2" smd circle
			(at -0.40005 0 180)
			(size 0 0)
			(layers "B.Cu" "B.Mask" "B.Paste")
			(net "GND")
		)
	)
	(footprint ""
		(layer "B.Cu")
		(at 302.487076 -399.722848 -90)
		(property "Reference" "C554"
			(at 0 0 90)
			(layer "B.SilkS")
			(hide yes)
			(effects
				(font
					(size 1.27 1.27)
				)
				(justify mirror)
			)
		)
		(property "Value" ""
			(at 0 0 90)
			(layer "B.Fab")
			(effects
				(font
					(size 1.27 1.27)
				)
				(justify mirror)
			)
		)
		(duplicate_pad_numbers_are_jumpers no)
		(fp_line
			(start -0.7874 0.4064)
			(end 0.7874 0.4064)
			(stroke
				(width 0.1524)
				(type default)
			)
			(layer "B.SilkS")
		)
		(fp_line
			(start 0.7874 0.4064)
			(end 0.7874 -0.4064)
			(stroke
				(width 0.1524)
				(type default)
			)
			(layer "B.SilkS")
		)
		(fp_line
			(start -0.7874 -0.4064)
			(end -0.7874 0.4064)
			(stroke
				(width 0.1524)
				(type default)
			)
			(layer "B.SilkS")
		)
		(fp_line
			(start 0.7874 -0.4064)
			(end -0.7874 -0.4064)
			(stroke
				(width 0.1524)
				(type default)
			)
			(layer "B.SilkS")
		)
		(fp_line
			(start -0.67945 0.3048)
			(end -0.120396 0.3048)
			(stroke
				(width 0.1)
				(type default)
			)
			(layer "B.Fab")
		)
		(fp_line
			(start -0.120396 0.3048)
			(end -0.120396 0.2794)
			(stroke
				(width 0.1)
				(type default)
			)
			(layer "B.Fab")
		)
		(fp_line
			(start 0.12065 0.3048)
			(end 0.67945 0.3048)
			(stroke
				(width 0.1)
				(type default)
			)
			(layer "B.Fab")
		)
		(fp_line
			(start 0.67945 0.3048)
			(end 0.67945 -0.305054)
			(stroke
				(width 0.1)
				(type default)
			)
			(layer "B.Fab")
		)
		(fp_line
			(start -0.120396 0.2794)
			(end 0.12065 0.2794)
			(stroke
				(width 0.1)
				(type default)
			)
			(layer "B.Fab")
		)
		(fp_line
			(start 0.12065 0.2794)
			(end 0.12065 0.3048)
			(stroke
				(width 0.1)
				(type default)
			)
			(layer "B.Fab")
		)
		(fp_line
			(start -0.12065 -0.2794)
			(end -0.12065 -0.3048)
			(stroke
				(width 0.1)
				(type default)
			)
			(layer "B.Fab")
		)
		(fp_line
			(start 0.12065 -0.2794)
			(end -0.12065 -0.2794)
			(stroke
				(width 0.1)
				(type default)
			)
			(layer "B.Fab")
		)
		(fp_line
			(start -0.67945 -0.3048)
			(end -0.67945 0.3048)
			(stroke
				(width 0.1)
				(type default)
			)
			(layer "B.Fab")
		)
		(fp_line
			(start -0.12065 -0.3048)
			(end -0.67945 -0.3048)
			(stroke
				(width 0.1)
				(type default)
			)
			(layer "B.Fab")
		)
		(fp_line
			(start 0.12065 -0.305054)
			(end 0.12065 -0.2794)
			(stroke
				(width 0.1)
				(type default)
			)
			(layer "B.Fab")
		)
		(fp_line
			(start 0.67945 -0.305054)
			(end 0.12065 -0.305054)
			(stroke
				(width 0.1)
				(type default)
			)
			(layer "B.Fab")
		)
		(pad "1" smd circle
			(at 0.40005 0 90)
			(size 0 0)
			(layers "B.Cu" "B.Mask" "B.Paste")
			(net "P0V9_CPU0_RT0_2A")
		)
		(pad "2" smd circle
			(at -0.40005 0 90)
			(size 0 0)
			(layers "B.Cu" "B.Mask" "B.Paste")
			(net "GND")
		)
	)
	(footprint ""
		(layer "B.Cu")
		(at 109.949996 -26.952448 90)
		(property "Reference" "C6103"
			(at 0 0 90)
			(layer "B.SilkS")
			(hide yes)
			(effects
				(font
					(size 1.27 1.27)
				)
				(justify mirror)
			)
		)
		(property "Value" ""
			(at 0 0 90)
			(layer "B.Fab")
			(effects
				(font
					(size 1.27 1.27)
				)
				(justify mirror)
			)
		)
		(duplicate_pad_numbers_are_jumpers no)
		(fp_line
			(start 0.7874 -0.4064)
			(end -0.7874 -0.4064)
			(stroke
				(width 0.1524)
				(type default)
			)
			(layer "B.SilkS")
		)
		(fp_line
			(start -0.7874 -0.4064)
			(end -0.7874 0.4064)
			(stroke
				(width 0.1524)
				(type default)
			)
			(layer "B.SilkS")
		)
		(fp_line
			(start 0.7874 0.4064)
			(end 0.7874 -0.4064)
			(stroke
				(width 0.1524)
				(type default)
			)
			(layer "B.SilkS")
		)
		(fp_line
			(start -0.7874 0.4064)
			(end 0.7874 0.4064)
			(stroke
				(width 0.1524)
				(type default)
			)
			(layer "B.SilkS")
		)
		(fp_line
			(start 0.67945 -0.305054)
			(end 0.12065 -0.305054)
			(stroke
				(width 0.1)
				(type default)
			)
			(layer "B.Fab")
		)
		(fp_line
			(start 0.12065 -0.305054)
			(end 0.12065 -0.2794)
			(stroke
				(width 0.1)
				(type default)
			)
			(layer "B.Fab")
		)
		(fp_line
			(start -0.12065 -0.3048)
			(end -0.67945 -0.3048)
			(stroke
				(width 0.1)
				(type default)
			)
			(layer "B.Fab")
		)
		(fp_line
			(start -0.67945 -0.3048)
			(end -0.67945 0.3048)
			(stroke
				(width 0.1)
				(type default)
			)
			(layer "B.Fab")
		)
		(fp_line
			(start 0.12065 -0.2794)
			(end -0.12065 -0.2794)
			(stroke
				(width 0.1)
				(type default)
			)
			(layer "B.Fab")
		)
		(fp_line
			(start -0.12065 -0.2794)
			(end -0.12065 -0.3048)
			(stroke
				(width 0.1)
				(type default)
			)
			(layer "B.Fab")
		)
		(fp_line
			(start 0.12065 0.2794)
			(end 0.12065 0.3048)
			(stroke
				(width 0.1)
				(type default)
			)
			(layer "B.Fab")
		)
		(fp_line
			(start -0.120396 0.2794)
			(end 0.12065 0.2794)
			(stroke
				(width 0.1)
				(type default)
			)
			(layer "B.Fab")
		)
		(fp_line
			(start 0.67945 0.3048)
			(end 0.67945 -0.305054)
			(stroke
				(width 0.1)
				(type default)
			)
			(layer "B.Fab")
		)
		(fp_line
			(start 0.12065 0.3048)
			(end 0.67945 0.3048)
			(stroke
				(width 0.1)
				(type default)
			)
			(layer "B.Fab")
		)
		(fp_line
			(start -0.120396 0.3048)
			(end -0.120396 0.2794)
			(stroke
				(width 0.1)
				(type default)
			)
			(layer "B.Fab")
		)
		(fp_line
			(start -0.67945 0.3048)
			(end -0.120396 0.3048)
			(stroke
				(width 0.1)
				(type default)
			)
			(layer "B.Fab")
		)
		(pad "1" smd circle
			(at 0.40005 0 270)
			(size 0 0)
			(layers "B.Cu" "B.Mask" "B.Paste")
			(net "P3V3_AUX_CPU0_USB2_AVDD33")
		)
		(pad "2" smd circle
			(at -0.40005 0 270)
			(size 0 0)
			(layers "B.Cu" "B.Mask" "B.Paste")
			(net "GND")
		)
	)
	(footprint ""
		(layer "B.Cu")
		(at 119.2784 -386.766562 90)
		(property "Reference" "C456"
			(at 0 0 90)
			(layer "B.SilkS")
			(hide yes)
			(effects
				(font
					(size 1.27 1.27)
				)
				(justify mirror)
			)
		)
		(property "Value" ""
			(at 0 0 90)
			(layer "B.Fab")
			(effects
				(font
					(size 1.27 1.27)
				)
				(justify mirror)
			)
		)
		(duplicate_pad_numbers_are_jumpers no)
		(fp_line
			(start 0.299974 -0.150114)
			(end -0.299974 -0.150114)
			(stroke
				(width 0.1)
				(type default)
			)
			(layer "B.Fab")
		)
		(fp_line
			(start -0.299974 -0.150114)
			(end -0.299974 0.150114)
			(stroke
				(width 0.1)
				(type default)
			)
			(layer "B.Fab")
		)
		(fp_line
			(start 0.299974 0.150114)
			(end 0.299974 -0.150114)
			(stroke
				(width 0.1)
				(type default)
			)
			(layer "B.Fab")
		)
		(fp_line
			(start -0.299974 0.150114)
			(end 0.299974 0.150114)
			(stroke
				(width 0.1)
				(type default)
			)
			(layer "B.Fab")
		)
		(pad "1" smd rect
			(at 0.2667 0 270)
			(size 0.3048 0.381)
			(layers "B.Cu" "B.Mask" "B.Paste")
			(net "P0V9_CPU1_RT3_2A_2D")
		)
		(pad "2" smd rect
			(at -0.2667 0 270)
			(size 0.3048 0.381)
			(layers "B.Cu" "B.Mask" "B.Paste")
			(net "GND")
		)
	)
	(footprint ""
		(layer "B.Cu")
		(at 197.269608 -121.753376 180)
		(property "Reference" "R3476"
			(at 0 0 0)
			(layer "B.SilkS")
			(hide yes)
			(effects
				(font
					(size 1.27 1.27)
				)
				(justify mirror)
			)
		)
		(property "Value" ""
			(at 0 0 0)
			(layer "B.Fab")
			(effects
				(font
					(size 1.27 1.27)
				)
				(justify mirror)
			)
		)
		(duplicate_pad_numbers_are_jumpers no)
		(fp_line
			(start 0.7874 0.4064)
			(end 0.7874 -0.4064)
			(stroke
				(width 0.1524)
				(type default)
			)
			(layer "B.SilkS")
		)
		(fp_line
			(start 0.7874 -0.4064)
			(end -0.7874 -0.4064)
			(stroke
				(width 0.1524)
				(type default)
			)
			(layer "B.SilkS")
		)
		(fp_line
			(start -0.7874 0.4064)
			(end 0.7874 0.4064)
			(stroke
				(width 0.1524)
				(type default)
			)
			(layer "B.SilkS")
		)
		(fp_line
			(start -0.7874 -0.4064)
			(end -0.7874 0.4064)
			(stroke
				(width 0.1524)
				(type default)
			)
			(layer "B.SilkS")
		)
		(fp_line
			(start 0.67945 0.3048)
			(end 0.67945 -0.305054)
			(stroke
				(width 0.1)
				(type default)
			)
			(layer "B.Fab")
		)
		(fp_line
			(start 0.67945 -0.305054)
			(end 0.12065 -0.305054)
			(stroke
				(width 0.1)
				(type default)
			)
			(layer "B.Fab")
		)
		(fp_line
			(start 0.12065 0.3048)
			(end 0.67945 0.3048)
			(stroke
				(width 0.1)
				(type default)
			)
			(layer "B.Fab")
		)
		(fp_line
			(start 0.12065 0.2794)
			(end 0.12065 0.3048)
			(stroke
				(width 0.1)
				(type default)
			)
			(layer "B.Fab")
		)
		(fp_line
			(start 0.12065 -0.2794)
			(end -0.12065 -0.2794)
			(stroke
				(width 0.1)
				(type default)
			)
			(layer "B.Fab")
		)
		(fp_line
			(start 0.12065 -0.305054)
			(end 0.12065 -0.2794)
			(stroke
				(width 0.1)
				(type default)
			)
			(layer "B.Fab")
		)
		(fp_line
			(start -0.120396 0.3048)
			(end -0.120396 0.2794)
			(stroke
				(width 0.1)
				(type default)
			)
			(layer "B.Fab")
		)
		(fp_line
			(start -0.120396 0.2794)
			(end 0.12065 0.2794)
			(stroke
				(width 0.1)
				(type default)
			)
			(layer "B.Fab")
		)
		(fp_line
			(start -0.12065 -0.2794)
			(end -0.12065 -0.3048)
			(stroke
				(width 0.1)
				(type default)
			)
			(layer "B.Fab")
		)
		(fp_line
			(start -0.12065 -0.3048)
			(end -0.67945 -0.3048)
			(stroke
				(width 0.1)
				(type default)
			)
			(layer "B.Fab")
		)
		(fp_line
			(start -0.67945 0.3048)
			(end -0.120396 0.3048)
			(stroke
				(width 0.1)
				(type default)
			)
			(layer "B.Fab")
		)
		(fp_line
			(start -0.67945 -0.3048)
			(end -0.67945 0.3048)
			(stroke
				(width 0.1)
				(type default)
			)
			(layer "B.Fab")
		)
		(pad "1" smd circle
			(at 0.40005 0)
			(size 0 0)
			(layers "B.Cu" "B.Mask" "B.Paste")
			(net "GPU_FPGA_THERM_OVERT_ISO_R_N")
		)
		(pad "2" smd circle
			(at -0.40005 0)
			(size 0 0)
			(layers "B.Cu" "B.Mask" "B.Paste")
			(net "GPU_FPGA_THERM_OVERT_ISO_N")
		)
	)
)
